(kicad_pcb
	(version 20260206)
	(generator "pcbnew")
	(generator_version "10.0")
	(general
		(thickness 1.6)
		(legacy_teardrops no)
	)
	(paper "A4")
	(title_block
		(title "peb — Lightning_PEB_BRD.brd")
		(comment 1 "Lightning (Wiwynn / Facebook NVMe JBOF) / footprints 2302-2309 of 2563")
	)
	(layers
		(0 "F.Cu" signal "TOP")
		(4 "In1.Cu" signal "L2GND")
		(6 "In2.Cu" signal "L3")
		(8 "In3.Cu" signal "L4VCC")
		(10 "In4.Cu" signal "L5VCC")
		(12 "In5.Cu" signal "L6")
		(14 "In6.Cu" signal "L7GND")
		(2 "B.Cu" signal "BOTTOM")
		(9 "F.Adhes" user "F.Adhesive")
		(11 "B.Adhes" user "B.Adhesive")
		(13 "F.Paste" user "Package Geometry/Pastemask Top")
		(15 "B.Paste" user "Package Geometry/Pastemask Bottom")
		(5 "F.SilkS" user "Ref Des/Silkscreen Top")
		(7 "B.SilkS" user "Ref Des/Silkscreen Bottom")
		(1 "F.Mask" user "Board Geometry/Soldermask Top")
		(3 "B.Mask" user "Board Geometry/Soldermask Bottom")
		(17 "Dwgs.User" user "User.Drawings")
		(19 "Cmts.User" user "User.Comments")
		(21 "Eco1.User" user "User.Eco1")
		(23 "Eco2.User" user "User.Eco2")
		(25 "Edge.Cuts" user "Board Geometry/Outline")
		(27 "Margin" user)
		(31 "F.CrtYd" user "Package Geometry/Place Bound Top")
		(29 "B.CrtYd" user "Package Geometry/Place Bound Bottom")
		(35 "F.Fab" user "Ref Des/Assembly Top")
		(33 "B.Fab" user "Ref Des/Assembly Bottom")
	)
	(footprint ""
		(layer "B.Cu")
		(at 41.021 -127 180)
		(property "Reference" "R301"
			(at 0 0 0)
			(layer "B.SilkS")
			(hide yes)
			(effects
				(font
					(size 1.27 1.27)
				)
				(justify mirror)
			)
		)
		(property "Value" "10KR2F-2-GP"
			(at -0.064008 -3.993896 180)
			(unlocked yes)
			(layer "B.Fab")
			(hide yes)
			(effects
				(font
					(size 1.016 1.016)
					(thickness 0.1524)
				)
				(justify mirror)
			)
		)
		(property "Device Type" "R402H16"
			(at -0.064008 -5.517896 180)
			(unlocked yes)
			(layer "B.Fab")
			(hide yes)
			(effects
				(font
					(size 1.016 1.016)
					(thickness 0.1524)
				)
				(justify mirror)
			)
		)
		(duplicate_pad_numbers_are_jumpers no)
		(fp_line
			(start 0.508 -0.9398)
			(end 0.508 0.9398)
			(stroke
				(width 0.1524)
				(type default)
			)
			(layer "B.SilkS")
		)
		(fp_line
			(start -0.508 -0.9398)
			(end 0.508 -0.9398)
			(stroke
				(width 0.1524)
				(type default)
			)
			(layer "B.SilkS")
		)
		(fp_rect
			(start 0.508 0.9398)
			(end -0.508 -0.9398)
			(stroke
				(width 0)
				(type default)
			)
			(fill no)
			(layer "B.CrtYd")
		)
		(fp_rect
			(start 0.508 0.9398)
			(end -0.508 -0.9398)
			(stroke
				(width 0)
				(type default)
			)
			(fill no)
			(layer "B.Fab")
		)
		(pad "1" smd custom
			(at 0 -0.4445)
			(size 0.1397 0.1397)
			(layers "B.Cu" "B.Mask" "B.Paste")
			(net "BMC0_ENTEST1")
			(options
				(clearance outline)
				(anchor circle)
			)
			(primitives
				(gr_poly
					(pts
						(arc
							(start -0.1778 0.2794)
							(mid -0.249642 0.249642)
							(end -0.2794 0.1778)
						)
						(arc
							(start -0.2794 -0.1778)
							(mid -0.249642 -0.249642)
							(end -0.1778 -0.2794)
						)
						(arc
							(start 0.1778 -0.2794)
							(mid 0.249642 -0.249642)
							(end 0.2794 -0.1778)
						)
						(arc
							(start 0.2794 0.1778)
							(mid 0.249642 0.249642)
							(end 0.1778 0.2794)
						)
					)
					(width 0)
					(fill yes)
				)
			)
		)
		(pad "2" smd custom
			(at 0 0.4445)
			(size 0.1397 0.1397)
			(layers "B.Cu" "B.Mask" "B.Paste")
			(net "GND")
			(options
				(clearance outline)
				(anchor circle)
			)
			(primitives
				(gr_poly
					(pts
						(arc
							(start -0.1778 0.2794)
							(mid -0.249642 0.249642)
							(end -0.2794 0.1778)
						)
						(arc
							(start -0.2794 -0.1778)
							(mid -0.249642 -0.249642)
							(end -0.1778 -0.2794)
						)
						(arc
							(start 0.1778 -0.2794)
							(mid 0.249642 -0.249642)
							(end 0.2794 -0.1778)
						)
						(arc
							(start 0.2794 0.1778)
							(mid 0.249642 0.249642)
							(end 0.1778 0.2794)
						)
					)
					(width 0)
					(fill yes)
				)
			)
		)
	)
	(footprint ""
		(layer "B.Cu")
		(at 228.6254 -53.001672 90)
		(property "Reference" "C563"
			(at 0 0 90)
			(layer "B.SilkS")
			(hide yes)
			(effects
				(font
					(size 1.27 1.27)
				)
				(justify mirror)
			)
		)
		(property "Value" "SCD1U16V1KX-1-GP"
			(at 2.8321 -1.7399 90)
			(unlocked yes)
			(layer "B.Fab")
			(hide yes)
			(effects
				(font
					(size 1.016 1.016)
					(thickness 0.1524)
				)
				(justify mirror)
			)
		)
		(property "Device Type" "C0201H13"
			(at 2.8321 -3.2639 90)
			(unlocked yes)
			(layer "B.Fab")
			(hide yes)
			(effects
				(font
					(size 1.016 1.016)
					(thickness 0.1524)
				)
				(justify mirror)
			)
		)
		(duplicate_pad_numbers_are_jumpers no)
		(fp_rect
			(start 0.2794 0.6477)
			(end -0.2794 -0.6477)
			(stroke
				(width 0)
				(type default)
			)
			(fill no)
			(layer "B.CrtYd")
		)
		(fp_rect
			(start 0.2794 0.6477)
			(end -0.2794 -0.6477)
			(stroke
				(width 0)
				(type default)
			)
			(fill no)
			(layer "B.Fab")
		)
		(pad "1" smd custom
			(at 0 -0.2794 270)
			(size 0.0762 0.0762)
			(layers "B.Cu" "B.Mask" "B.Paste")
			(net "DUT_AVD_PCIE")
			(options
				(clearance outline)
				(anchor circle)
			)
			(primitives
				(gr_poly
					(pts
						(arc
							(start 0.1524 0.127)
							(mid 0.137521 0.162921)
							(end 0.1016 0.1778)
						)
						(arc
							(start -0.1016 0.1778)
							(mid -0.137521 0.162921)
							(end -0.1524 0.127)
						)
						(arc
							(start -0.1524 -0.127)
							(mid -0.137521 -0.162921)
							(end -0.1016 -0.1778)
						)
						(arc
							(start 0.1016 -0.1778)
							(mid 0.137521 -0.162921)
							(end 0.1524 -0.127)
						)
					)
					(width 0)
					(fill yes)
				)
			)
		)
		(pad "2" smd custom
			(at 0 0.2794 270)
			(size 0.0762 0.0762)
			(layers "B.Cu" "B.Mask" "B.Paste")
			(net "GND")
			(options
				(clearance outline)
				(anchor circle)
			)
			(primitives
				(gr_poly
					(pts
						(arc
							(start 0.1524 0.127)
							(mid 0.137521 0.162921)
							(end 0.1016 0.1778)
						)
						(arc
							(start -0.1016 0.1778)
							(mid -0.137521 0.162921)
							(end -0.1524 0.127)
						)
						(arc
							(start -0.1524 -0.127)
							(mid -0.137521 -0.162921)
							(end -0.1016 -0.1778)
						)
						(arc
							(start 0.1016 -0.1778)
							(mid 0.137521 -0.162921)
							(end 0.1524 -0.127)
						)
					)
					(width 0)
					(fill yes)
				)
			)
		)
	)
	(footprint ""
		(layer "B.Cu")
		(at 310.007 -62.357 180)
		(property "Reference" "PG54"
			(at 0 0 0)
			(layer "B.SilkS")
			(hide yes)
			(effects
				(font
					(size 1.27 1.27)
				)
				(justify mirror)
			)
		)
		(property "Value" "GAP-CLOSE-PWR-3-GP"
			(at -0.0254 -6.5786 180)
			(unlocked yes)
			(layer "B.Fab")
			(hide yes)
			(effects
				(font
					(size 1.016 1.016)
					(thickness 0.1524)
				)
				(justify mirror)
			)
		)
		(property "Device Type" "GAP-CLOSE-PWR-3"
			(at -0.0254 -8.255 180)
			(unlocked yes)
			(layer "B.Fab")
			(hide yes)
			(effects
				(font
					(size 1.016 1.016)
					(thickness 0.1524)
				)
				(justify mirror)
			)
		)
		(duplicate_pad_numbers_are_jumpers no)
		(fp_rect
			(start 0.7112 0.4572)
			(end -0.7112 -0.4572)
			(stroke
				(width 0)
				(type default)
			)
			(fill no)
			(layer "B.CrtYd")
		)
		(fp_poly
			(pts
				(xy 0.7112 -0.4572) (xy -0.7112 -0.4572) (xy -0.7112 0.4572) (xy 0.7112 0.4572)
			)
			(stroke
				(width 0)
				(type default)
			)
			(fill no)
			(layer "B.Fab")
		)
		(pad "1" smd rect
			(at 0.3048 0)
			(size 0.6604 0.762)
			(layers "B.Cu" "B.Mask" "B.Paste")
			(net "DUT_VDD")
		)
		(pad "2" smd rect
			(at -0.3048 0)
			(size 0.6604 0.762)
			(layers "B.Cu" "B.Mask" "B.Paste")
			(net "P0V9_E")
		)
	)
	(footprint ""
		(layer "B.Cu")
		(at 272.6055 -7.8105 180)
		(property "Reference" "R277"
			(at 0 0 0)
			(layer "B.SilkS")
			(hide yes)
			(effects
				(font
					(size 1.27 1.27)
				)
				(justify mirror)
			)
		)
		(property "Value" "0R2J-2-GP"
			(at -0.064008 -3.993896 180)
			(unlocked yes)
			(layer "B.Fab")
			(hide yes)
			(effects
				(font
					(size 1.016 1.016)
					(thickness 0.1524)
				)
				(justify mirror)
			)
		)
		(property "Device Type" "R402H16"
			(at -0.064008 -5.517896 180)
			(unlocked yes)
			(layer "B.Fab")
			(hide yes)
			(effects
				(font
					(size 1.016 1.016)
					(thickness 0.1524)
				)
				(justify mirror)
			)
		)
		(duplicate_pad_numbers_are_jumpers no)
		(fp_line
			(start 0.508 -0.9398)
			(end 0.508 0.9398)
			(stroke
				(width 0.1524)
				(type default)
			)
			(layer "B.SilkS")
		)
		(fp_line
			(start -0.508 -0.9398)
			(end 0.508 -0.9398)
			(stroke
				(width 0.1524)
				(type default)
			)
			(layer "B.SilkS")
		)
		(fp_rect
			(start 0.508 0.9398)
			(end -0.508 -0.9398)
			(stroke
				(width 0)
				(type default)
			)
			(fill no)
			(layer "B.CrtYd")
		)
		(fp_rect
			(start 0.508 0.9398)
			(end -0.508 -0.9398)
			(stroke
				(width 0)
				(type default)
			)
			(fill no)
			(layer "B.Fab")
		)
		(pad "1" smd custom
			(at 0 -0.4445)
			(size 0.1397 0.1397)
			(layers "B.Cu" "B.Mask" "B.Paste")
			(net "MINISAS_CN16_A_I2C_INT#")
			(options
				(clearance outline)
				(anchor circle)
			)
			(primitives
				(gr_poly
					(pts
						(arc
							(start -0.1778 0.2794)
							(mid -0.249642 0.249642)
							(end -0.2794 0.1778)
						)
						(arc
							(start -0.2794 -0.1778)
							(mid -0.249642 -0.249642)
							(end -0.1778 -0.2794)
						)
						(arc
							(start 0.1778 -0.2794)
							(mid 0.249642 -0.249642)
							(end 0.2794 -0.1778)
						)
						(arc
							(start 0.2794 0.1778)
							(mid 0.249642 0.249642)
							(end 0.1778 0.2794)
						)
					)
					(width 0)
					(fill yes)
				)
			)
		)
		(pad "2" smd custom
			(at 0 0.4445)
			(size 0.1397 0.1397)
			(layers "B.Cu" "B.Mask" "B.Paste")
			(net "PCIE_REFCLK_H0_N_R")
			(options
				(clearance outline)
				(anchor circle)
			)
			(primitives
				(gr_poly
					(pts
						(arc
							(start -0.1778 0.2794)
							(mid -0.249642 0.249642)
							(end -0.2794 0.1778)
						)
						(arc
							(start -0.2794 -0.1778)
							(mid -0.249642 -0.249642)
							(end -0.1778 -0.2794)
						)
						(arc
							(start 0.1778 -0.2794)
							(mid 0.249642 -0.249642)
							(end 0.2794 -0.1778)
						)
						(arc
							(start 0.2794 0.1778)
							(mid 0.249642 0.249642)
							(end 0.1778 0.2794)
						)
					)
					(width 0)
					(fill yes)
				)
			)
		)
	)
	(footprint ""
		(layer "B.Cu")
		(at 61.4426 -115.7224 90)
		(property "Reference" "R300"
			(at 0 0 90)
			(layer "B.SilkS")
			(hide yes)
			(effects
				(font
					(size 1.27 1.27)
				)
				(justify mirror)
			)
		)
		(property "Value" "4K7R2F-GP"
			(at -0.064008 -3.993896 90)
			(unlocked yes)
			(layer "B.Fab")
			(hide yes)
			(effects
				(font
					(size 1.016 1.016)
					(thickness 0.1524)
				)
				(justify mirror)
			)
		)
		(property "Device Type" "R402H16"
			(at -0.064008 -5.517896 90)
			(unlocked yes)
			(layer "B.Fab")
			(hide yes)
			(effects
				(font
					(size 1.016 1.016)
					(thickness 0.1524)
				)
				(justify mirror)
			)
		)
		(duplicate_pad_numbers_are_jumpers no)
		(fp_line
			(start 0.508 -0.9398)
			(end 0.508 0.9398)
			(stroke
				(width 0.1524)
				(type default)
			)
			(layer "B.SilkS")
		)
		(fp_line
			(start -0.508 -0.9398)
			(end 0.508 -0.9398)
			(stroke
				(width 0.1524)
				(type default)
			)
			(layer "B.SilkS")
		)
		(fp_rect
			(start 0.508 0.9398)
			(end -0.508 -0.9398)
			(stroke
				(width 0)
				(type default)
			)
			(fill no)
			(layer "B.CrtYd")
		)
		(fp_rect
			(start 0.508 0.9398)
			(end -0.508 -0.9398)
			(stroke
				(width 0)
				(type default)
			)
			(fill no)
			(layer "B.Fab")
		)
		(pad "1" smd custom
			(at 0 -0.4445 270)
			(size 0.1397 0.1397)
			(layers "B.Cu" "B.Mask" "B.Paste")
			(net "P3V3_STBY")
			(options
				(clearance outline)
				(anchor circle)
			)
			(primitives
				(gr_poly
					(pts
						(arc
							(start -0.1778 0.2794)
							(mid -0.249642 0.249642)
							(end -0.2794 0.1778)
						)
						(arc
							(start -0.2794 -0.1778)
							(mid -0.249642 -0.249642)
							(end -0.1778 -0.2794)
						)
						(arc
							(start 0.1778 -0.2794)
							(mid 0.249642 -0.249642)
							(end 0.2794 -0.1778)
						)
						(arc
							(start 0.2794 0.1778)
							(mid 0.249642 0.249642)
							(end 0.1778 0.2794)
						)
					)
					(width 0)
					(fill yes)
				)
			)
		)
		(pad "2" smd custom
			(at 0 0.4445 270)
			(size 0.1397 0.1397)
			(layers "B.Cu" "B.Mask" "B.Paste")
			(net "I2C3_LS_G2")
			(options
				(clearance outline)
				(anchor circle)
			)
			(primitives
				(gr_poly
					(pts
						(arc
							(start -0.1778 0.2794)
							(mid -0.249642 0.249642)
							(end -0.2794 0.1778)
						)
						(arc
							(start -0.2794 -0.1778)
							(mid -0.249642 -0.249642)
							(end -0.1778 -0.2794)
						)
						(arc
							(start 0.1778 -0.2794)
							(mid 0.249642 -0.249642)
							(end 0.2794 -0.1778)
						)
						(arc
							(start 0.2794 0.1778)
							(mid 0.249642 0.249642)
							(end 0.1778 0.2794)
						)
					)
					(width 0)
					(fill yes)
				)
			)
		)
	)
	(footprint ""
		(layer "B.Cu")
		(at 51.181 -145.415 180)
		(property "Reference" "SR849"
			(at 0 0 0)
			(layer "B.SilkS")
			(hide yes)
			(effects
				(font
					(size 1.27 1.27)
				)
				(justify mirror)
			)
		)
		(property "Value" "4K75R2F-1-GP"
			(at -0.064008 -3.993896 180)
			(unlocked yes)
			(layer "B.Fab")
			(hide yes)
			(effects
				(font
					(size 1.016 1.016)
					(thickness 0.1524)
				)
				(justify mirror)
			)
		)
		(property "Device Type" "R402H16"
			(at -0.064008 -5.517896 180)
			(unlocked yes)
			(layer "B.Fab")
			(hide yes)
			(effects
				(font
					(size 1.016 1.016)
					(thickness 0.1524)
				)
				(justify mirror)
			)
		)
		(duplicate_pad_numbers_are_jumpers no)
		(fp_line
			(start 0.508 -0.9398)
			(end 0.508 0.9398)
			(stroke
				(width 0.1524)
				(type default)
			)
			(layer "B.SilkS")
		)
		(fp_line
			(start -0.508 -0.9398)
			(end 0.508 -0.9398)
			(stroke
				(width 0.1524)
				(type default)
			)
			(layer "B.SilkS")
		)
		(fp_rect
			(start 0.508 0.9398)
			(end -0.508 -0.9398)
			(stroke
				(width 0)
				(type default)
			)
			(fill no)
			(layer "B.CrtYd")
		)
		(fp_rect
			(start 0.508 0.9398)
			(end -0.508 -0.9398)
			(stroke
				(width 0)
				(type default)
			)
			(fill no)
			(layer "B.Fab")
		)
		(pad "1" smd custom
			(at 0 -0.4445)
			(size 0.1397 0.1397)
			(layers "B.Cu" "B.Mask" "B.Paste")
			(net "BMC_FW_DET_BOARD_VER_1")
			(options
				(clearance outline)
				(anchor circle)
			)
			(primitives
				(gr_poly
					(pts
						(arc
							(start -0.1778 0.2794)
							(mid -0.249642 0.249642)
							(end -0.2794 0.1778)
						)
						(arc
							(start -0.2794 -0.1778)
							(mid -0.249642 -0.249642)
							(end -0.1778 -0.2794)
						)
						(arc
							(start 0.1778 -0.2794)
							(mid 0.249642 -0.249642)
							(end 0.2794 -0.1778)
						)
						(arc
							(start 0.2794 0.1778)
							(mid 0.249642 0.249642)
							(end 0.1778 0.2794)
						)
					)
					(width 0)
					(fill yes)
				)
			)
		)
		(pad "2" smd custom
			(at 0 0.4445)
			(size 0.1397 0.1397)
			(layers "B.Cu" "B.Mask" "B.Paste")
			(net "GND")
			(options
				(clearance outline)
				(anchor circle)
			)
			(primitives
				(gr_poly
					(pts
						(arc
							(start -0.1778 0.2794)
							(mid -0.249642 0.249642)
							(end -0.2794 0.1778)
						)
						(arc
							(start -0.2794 -0.1778)
							(mid -0.249642 -0.249642)
							(end -0.1778 -0.2794)
						)
						(arc
							(start 0.1778 -0.2794)
							(mid 0.249642 -0.249642)
							(end 0.2794 -0.1778)
						)
						(arc
							(start 0.2794 0.1778)
							(mid 0.249642 0.249642)
							(end 0.1778 0.2794)
						)
					)
					(width 0)
					(fill yes)
				)
			)
		)
	)
	(footprint ""
		(layer "B.Cu")
		(at 34.937954 -158.479744 180)
		(property "Reference" "C197"
			(at 0 0 0)
			(layer "B.SilkS")
			(hide yes)
			(effects
				(font
					(size 1.27 1.27)
				)
				(justify mirror)
			)
		)
		(property "Value" "SC1U10V2KX-4-GP"
			(at -1.1811 -2.7051 180)
			(unlocked yes)
			(layer "B.Fab")
			(hide yes)
			(effects
				(font
					(size 1.016 1.016)
					(thickness 0.1524)
				)
				(justify mirror)
			)
		)
		(property "Device Type" "C402H22"
			(at -1.1811 -4.2291 180)
			(unlocked yes)
			(layer "B.Fab")
			(hide yes)
			(effects
				(font
					(size 1.016 1.016)
					(thickness 0.1524)
				)
				(justify mirror)
			)
		)
		(duplicate_pad_numbers_are_jumpers no)
		(fp_rect
			(start 0.4318 0.9525)
			(end -0.4318 -0.9525)
			(stroke
				(width 0)
				(type default)
			)
			(fill no)
			(layer "B.CrtYd")
		)
		(fp_rect
			(start 0.4318 0.9525)
			(end -0.4318 -0.9525)
			(stroke
				(width 0)
				(type default)
			)
			(fill no)
			(layer "B.Fab")
		)
		(pad "1" smd custom
			(at 0 -0.4445)
			(size 0.1524 0.1524)
			(layers "B.Cu" "B.Mask" "B.Paste")
			(net "P1V53_STBY")
			(options
				(clearance outline)
				(anchor circle)
			)
			(primitives
				(gr_poly
					(pts
						(arc
							(start 0.3048 0.2032)
							(mid 0.275042 0.275042)
							(end 0.2032 0.3048)
						)
						(arc
							(start -0.2032 0.3048)
							(mid -0.275042 0.275042)
							(end -0.3048 0.2032)
						)
						(arc
							(start -0.3048 -0.2032)
							(mid -0.275042 -0.275042)
							(end -0.2032 -0.3048)
						)
						(arc
							(start 0.2032 -0.3048)
							(mid 0.275042 -0.275042)
							(end 0.3048 -0.2032)
						)
					)
					(width 0)
					(fill yes)
				)
			)
		)
		(pad "2" smd custom
			(at 0 0.4445)
			(size 0.1524 0.1524)
			(layers "B.Cu" "B.Mask" "B.Paste")
			(net "GND")
			(options
				(clearance outline)
				(anchor circle)
			)
			(primitives
				(gr_poly
					(pts
						(arc
							(start 0.3048 0.2032)
							(mid 0.275042 0.275042)
							(end 0.2032 0.3048)
						)
						(arc
							(start -0.2032 0.3048)
							(mid -0.275042 0.275042)
							(end -0.3048 0.2032)
						)
						(arc
							(start -0.3048 -0.2032)
							(mid -0.275042 -0.275042)
							(end -0.2032 -0.3048)
						)
						(arc
							(start 0.2032 -0.3048)
							(mid 0.275042 -0.275042)
							(end 0.3048 -0.2032)
						)
					)
					(width 0)
					(fill yes)
				)
			)
		)
	)
	(footprint ""
		(layer "B.Cu")
		(at 212.916008 -4.064)
		(property "Reference" "R3716"
			(at 0 0 0)
			(layer "B.SilkS")
			(hide yes)
			(effects
				(font
					(size 1.27 1.27)
				)
				(justify mirror)
			)
		)
		(property "Value" "1KR2F-3-GP"
			(at -0.064008 -3.993896 0)
			(unlocked yes)
			(layer "B.Fab")
			(hide yes)
			(effects
				(font
					(size 1.016 1.016)
					(thickness 0.1524)
				)
				(justify mirror)
			)
		)
		(property "Device Type" "R402H16"
			(at -0.064008 -5.517896 0)
			(unlocked yes)
			(layer "B.Fab")
			(hide yes)
			(effects
				(font
					(size 1.016 1.016)
					(thickness 0.1524)
				)
				(justify mirror)
			)
		)
		(duplicate_pad_numbers_are_jumpers no)
		(fp_line
			(start -0.508 -0.9398)
			(end 0.508 -0.9398)
			(stroke
				(width 0.1524)
				(type default)
			)
			(layer "B.SilkS")
		)
		(fp_line
			(start 0.508 -0.9398)
			(end 0.508 0.9398)
			(stroke
				(width 0.1524)
				(type default)
			)
			(layer "B.SilkS")
		)
		(fp_rect
			(start 0.508 0.9398)
			(end -0.508 -0.9398)
			(stroke
				(width 0)
				(type default)
			)
			(fill no)
			(layer "B.CrtYd")
		)
		(fp_rect
			(start 0.508 0.9398)
			(end -0.508 -0.9398)
			(stroke
				(width 0)
				(type default)
			)
			(fill no)
			(layer "B.Fab")
		)
		(pad "1" smd custom
			(at 0 -0.4445 180)
			(size 0.1397 0.1397)
			(layers "B.Cu" "B.Mask" "B.Paste")
			(net "HOST4_RST_N")
			(options
				(clearance outline)
				(anchor circle)
			)
			(primitives
				(gr_poly
					(pts
						(arc
							(start -0.1778 0.2794)
							(mid -0.249642 0.249642)
							(end -0.2794 0.1778)
						)
						(arc
							(start -0.2794 -0.1778)
							(mid -0.249642 -0.249642)
							(end -0.1778 -0.2794)
						)
						(arc
							(start 0.1778 -0.2794)
							(mid 0.249642 -0.249642)
							(end 0.2794 -0.1778)
						)
						(arc
							(start 0.2794 0.1778)
							(mid 0.249642 0.249642)
							(end 0.1778 0.2794)
						)
					)
					(width 0)
					(fill yes)
				)
			)
		)
		(pad "2" smd custom
			(at 0 0.4445 180)
			(size 0.1397 0.1397)
			(layers "B.Cu" "B.Mask" "B.Paste")
			(net "P3V3_STBY")
			(options
				(clearance outline)
				(anchor circle)
			)
			(primitives
				(gr_poly
					(pts
						(arc
							(start -0.1778 0.2794)
							(mid -0.249642 0.249642)
							(end -0.2794 0.1778)
						)
						(arc
							(start -0.2794 -0.1778)
							(mid -0.249642 -0.249642)
							(end -0.1778 -0.2794)
						)
						(arc
							(start 0.1778 -0.2794)
							(mid 0.249642 -0.249642)
							(end 0.2794 -0.1778)
						)
						(arc
							(start 0.2794 0.1778)
							(mid 0.249642 0.249642)
							(end 0.1778 0.2794)
						)
					)
					(width 0)
					(fill yes)
				)
			)
		)
	)
)
